FILE_TYPE = CONNECTIVITY;
{Allegro Design Entry HDL 17.2-2016 S081 (4005846) 1/11/2022}
"PAGE_NUMBER" = 193;
0"NC";
1"GND\g";
2"GND\g";
3"GND\g";
4"GND\g";
5"GND\g";
6"GND\g";
7"GND\g";
8"GND\g";
9"GND\g";
10"GND\g";
11"P5V_STBY\g";
12"P3V3_STBY\g";
13"P12V_STBY\g";
14"PVDDCR_CPU1_P1\g";
15"GND\g";
16"PVDDCR_CPU1_P1_TEMP0";
17"PVDDCR_CPU1_P1\g";
18"PVDDCR_CPU1_P1_VOS1";
19"GND\g";
20"PVDDCR_CPU1_P1_VCC1";
21"SW_PVDDCR_CPU1_P1_BOOTR2";
22"SW_PVDDCR_CPU1_P1_SW2";
23"IND_CPU1_P1_CPL1";
24"SW_PVDDCR_CPU1_P1_BOOT1_R";
25"NC_PVDDCR_CPU1_P1_GL2_1";
26"PVDDCR_CPU1_P1_PVCC\g";
27"PVDDCR_CPU1_P1_LSET1";
28"PVDDCR_CPU1_P1_LSET2";
29"PVDDCR_CPU1_P1_VCC2";
30"PVDDCR_CPU1_P1_IMON2";
31"PVDDCR_CPU1_P1_PWM1";
32"PVDDCR_CPU1_P1_PWM2";
33"PVDDCR_CPU1_P1_TEMP0";
34"NC_PVDDCR_CPU1_P1_DNC2";
35"GND\g";
36"SW_P12V_STBY_PVDDCR_CPU1_P1_FLT\g";
37"SW_PVDDCR_CPU1_P1_BOOT2";
38"NC_PVDDCR_CPU1_P1_GL1_2";
39"NC_PVDDCR_CPU1_P1_GL2_2";
40"PVDDCR_CPU1_P1_VOS2";
41"SW_PVDDCR_CPU1_P1_SW2_RC";
42"SW_PVDDCR_CPU1_P1_SW1_RC";
43"NC_PVDDCR_CPU1_P1_DNC1";
44"SW_P12V_STBY_PVDDCR_CPU1_P1_FLT\g";
45"NC_PVDDCR_CPU1_P1_GL1_1";
46"SW_PVDDCR_CPU1_P1_BOOT1";
47"IND_CPU1_P1_CPL5";
48"IND_CPU1_P1_CPL2";
49"PVDDCR_CPU1_P1\g";
50"GND\g";
51"GND\g";
52"IND_CPU1_P1_CPL1";
53"GND\g";
54"SW_PVDDCR_CPU1_P1_BOOT2_R";
55"SW_PVDDCR_CPU1_P1_BOOTR1";
56"SW_PVDDCR_CPU1_P1_SW1";
57"GND\g";
58"PVDDCR_CPU1_P1_VCCS"CDS_PHYS_NET_NAME"PVCCIN_CPU0_VREF";
59"PVDDCR_CPU1_P1_IMON1";
60"PVDDCR_CPU1_P1_PVCC\g";
61"PVDDCR_CPU1_P1_VCCS"CDS_PHYS_NET_NAME"PVCCIN_CPU0_VREF";
%"UNIVERSAL_GND"
"1","(-8875,1100)","0","pure_quanta_power","I1";
;
CDS_LIB"pure_quanta_power"
HDL_POWER"GND";
"A"1;
%"VCC_CORE"
"1","(-1025,4600)","0","pure_quanta_power","I106";
;
HDL_POWER"PVDDCR_CPU1_P1"
CDS_LIB"pure_quanta_power";
"A"17;
%"UNIVERSAL_GND"
"1","(-1025,3875)","0","pure_quanta_power","I107";
;
CDS_LIB"pure_quanta_power"
HDL_POWER"GND";
"A"51;
%"Q_CAP"
"1","(-1375,4250)","0","pure_quanta","I108";
;
LOCATION"PC398_1"
$SEC"1"
CDS_SEC"1"
MATERIAL"X6S"
TOLERANCE"20%"
VALUE"22UF"
VOLTAGE"4V"
PACK_TYPE"0805"
CDS_LIB"pure_quanta"
PART_NUMBER"TMP_QCH622KMEA01";
"B"
$PN"2"51;
"A"
$PN"1"17;
%"Q_CAP"
"1","(-1800,4250)","0","pure_quanta","I109";
;
LOCATION"PC395_1"
$SEC"1"
CDS_SEC"1"
MATERIAL"X6S"
TOLERANCE"20%"
VALUE"22UF"
PART_NUMBER"TMP_QCH622KMEA01"
VOLTAGE"4V"
PACK_TYPE"0805"
CDS_LIB"pure_quanta";
"B"
$PN"2"51;
"A"
$PN"1"17;
%"Q_CAP"
"1","(-2150,4250)","0","pure_quanta","I111";
;
LOCATION"PC392"
$SEC"1"
CDS_SEC"1"
MATERIAL"X7R"
TOLERANCE"10%"
VALUE"0.1UF"
PART_NUMBER"CH4104K1B00"
VOLTAGE"25V"
PACK_TYPE"0402"
CDS_LIB"pure_quanta";
"B"
$PN"2"51;
"A"
$PN"1"17;
%"Q_RES"
"1","(-3900,3425)","0","pure_quanta","I112";
;
LOCATION"PR261"
$SEC"1"
CDS_SEC"1"
VALUE"0"
PART_NUMBER"CS00002JB38"
WATTAGE"1/16W"
MATERIAL"CHIP"
TOLERANCE"5%"
PACK_TYPE"0402LF"
CDS_LIB"pure_quanta";
"B"
$PN"2"17;
"A"
$PN"1"18;
%"Q_RES"
"1","(-4625,600)","0","pure_quanta","I124";
;
LOCATION"PR260"
$SEC"1"
CDS_SEC"1"
WATTAGE"1/16W"
MATERIAL"CHIP"
TOLERANCE"5%"
VALUE"0"
PART_NUMBER"CS00002JB38"
PACK_TYPE"0402LF"
CDS_LIB"pure_quanta";
"B"
$PN"2"49;
"A"
$PN"1"40;
%"UNIVERSAL_GND"
"1","(-1350,1300)","0","pure_quanta_power","I125";
;
CDS_LIB"pure_quanta_power"
HDL_POWER"GND";
"A"50;
%"VCC_CORE"
"1","(-1350,1925)","0","pure_quanta_power","I126";
;
HDL_POWER"PVDDCR_CPU1_P1"
CDS_LIB"pure_quanta_power";
"A"49;
%"Q_CAP"
"1","(-1350,1625)","0","pure_quanta","I127";
;
LOCATION"PC397_2"
$SEC"1"
CDS_SEC"1"
MATERIAL"X6S"
TOLERANCE"20%"
VALUE"22UF"
PART_NUMBER"TMP_QCH622KMEA01"
VOLTAGE"4V"
PACK_TYPE"0805"
CDS_LIB"pure_quanta";
"B"
$PN"2"50;
"A"
$PN"1"49;
%"Q_CAP"
"1","(-1775,1625)","0","pure_quanta","I128";
;
LOCATION"PC394_2"
$SEC"1"
CDS_SEC"1"
MATERIAL"X6S"
TOLERANCE"20%"
VALUE"22UF"
PART_NUMBER"TMP_QCH622KMEA01"
VOLTAGE"4V"
PACK_TYPE"0805"
CDS_LIB"pure_quanta";
"B"
$PN"2"50;
"A"
$PN"1"49;
%"UNIVERSAL_GND"
"1","(-8850,3725)","0","pure_quanta_power","I13";
;
CDS_LIB"pure_quanta_power"
HDL_POWER"GND";
"A"2;
%"Q_INDUCTOR4P_14"
"1","(-3175,1700)","0","pure_quanta","I137";
;
LOCATION"PL41"
$SEC"1"
CDS_SEC"1"
PART_TYPE"SMLF"
MATERIAL"IND"
PART_NUMBER"CV+15^0TZ04"
VALUE"150NH"
NEEDS_NO_SIZE"TRUE"
CDS_LIB"pure_quanta";
"1"
$PN"1"22;
"4"
$PN"4"49;
"3"
$PN"3"48;
"2"
$PN"2"23;
%"Q_INDUCTOR4P_14"
"1","(-3575,4325)","0","pure_quanta","I138";
;
LOCATION"PL40"
$SEC"1"
CDS_SEC"1"
MATERIAL"IND"
PART_TYPE"SMLF"
VALUE"150NH"
PART_NUMBER"CV+15^0TZ04"
CDS_LIB"pure_quanta"
NEEDS_NO_SIZE"TRUE";
"1"
$PN"1"56;
"4"
$PN"4"17;
"3"
$PN"3"52;
"2"
$PN"2"47;
%"Q_CAP"
"1","(-9375,1450)","0","pure_quanta","I139";
;
LOCATION"PC373_2"
$SEC"1"
CDS_SEC"1"
MATERIAL"X7R"
PART_NUMBER"CH4104K1B00"
PACK_TYPE"0402"
VALUE"0.1UF"
VOLTAGE"25V"
TOLERANCE"10%"
CDS_LIB"pure_quanta";
"B"
$PN"2"8;
"A"
$PN"1"61;
%"Q_RES"
"2","(-8850,3950)","2","pure_quanta","I14";
;
LOCATION"PR255"
$SEC"1"
CDS_SEC"1"
WATTAGE"1/16W"
MATERIAL"EMPTY"
TOLERANCE"1%"
VALUE"8.87K"
PART_NUMBER"CS28872FB01"
PACK_TYPE"0402LF"
CDS_LIB"pure_quanta";
"A"
$PN"1"27;
"B"
$PN"2"2;
%"Q_CAP"
"1","(-9350,4075)","0","pure_quanta","I140";
;
LOCATION"PC374_1"
$SEC"1"
CDS_SEC"1"
MATERIAL"X7R"
TOLERANCE"10%"
VALUE"0.1UF"
PART_NUMBER"CH4104K1B00"
VOLTAGE"25V"
PACK_TYPE"0402"
CDS_LIB"pure_quanta";
"B"
$PN"2"7;
"A"
$PN"1"58;
%"Q_CAP"
"1","(-4600,4675)","0","pure_quanta","I141";
;
LOCATION"PC383"
$SEC"1"
CDS_SEC"1"
VALUE"0.22UF"
PART_NUMBER"CH4223K1B00"
VOLTAGE"16V"
PACK_TYPE"0402"
MATERIAL"X7R"
TOLERANCE"10%"
CDS_LIB"pure_quanta";
"B"
$PN"2"55;
"A"
$PN"1"24;
%"Q_RES"
"1","(-5675,4800)","0","pure_quanta","I142";
;
LOCATION"PR258"
$SEC"1"
CDS_SEC"1"
PACK_TYPE"0402LF"
TOLERANCE"1%"
MATERIAL"CHIP"
WATTAGE"1/16W"
VALUE"4.7"
PART_NUMBER"CS-4702FB19"
CDS_LIB"pure_quanta";
"B"
$PN"2"24;
"A"
$PN"1"46;
%"Q_CAP"
"1","(-4475,2050)","0","pure_quanta","I143";
;
LOCATION"PC386"
$SEC"1"
CDS_SEC"1"
MATERIAL"X7R"
TOLERANCE"10%"
VALUE"0.22UF"
PART_NUMBER"CH4223K1B00"
VOLTAGE"16V"
PACK_TYPE"0402"
CDS_LIB"pure_quanta";
"B"
$PN"2"21;
"A"
$PN"1"54;
%"Q_RES"
"1","(-5625,2175)","0","pure_quanta","I144";
;
LOCATION"PR259"
$SEC"1"
CDS_SEC"1"
PACK_TYPE"0402LF"
MATERIAL"CHIP"
TOLERANCE"1%"
WATTAGE"1/16W"
VALUE"4.7"
PART_NUMBER"CS-4702FB19"
CDS_LIB"pure_quanta";
"B"
$PN"2"54;
"A"
$PN"1"37;
%"Q_CAPP"
"1","(-2575,2775)","0","pure_quanta","I148";
;
LOCATION"PC387"
$SEC"1"
CDS_SEC"1"
PACK_TYPE"SMLF"
VALUE"220UF"
TOLERANCE"20%"
MATERIAL"SPCAP"
PART_NUMBER"CH122KM8801"
VOLTAGE"4V"
CDS_LIB"pure_quanta";
"A"
$PN"1"14;
"B"
$PN"2"15;
%"UNIVERSAL_GND"
"1","(-1625,2400)","0","pure_quanta_power","I149";
;
CDS_LIB"pure_quanta_power"
HDL_POWER"GND";
"A"15;
%"Q_CAPP"
"1","(-2250,2775)","0","pure_quanta","I150";
;
LOCATION"PC388"
$SEC"1"
CDS_SEC"1"
VALUE"220UF"
TOLERANCE"20%"
VOLTAGE"4V"
MATERIAL"SPCAP"
PART_NUMBER"CH122KM8801"
PACK_TYPE"SMLF"
CDS_LIB"pure_quanta";
"A"
$PN"1"14;
"B"
$PN"2"15;
%"Q_CAPP"
"1","(-1925,2775)","0","pure_quanta","I151";
;
LOCATION"PC389"
$SEC"1"
CDS_SEC"1"
PACK_TYPE"SMLF"
VOLTAGE"4V"
VALUE"220UF"
TOLERANCE"20%"
MATERIAL"SPCAP"
PART_NUMBER"CH122KM8801"
CDS_LIB"pure_quanta";
"A"
$PN"1"14;
"B"
$PN"2"15;
%"VCC_CORE"
"1","(-1625,3075)","0","pure_quanta_power","I152";
;
HDL_POWER"PVDDCR_CPU1_P1"
CDS_LIB"pure_quanta_power";
"A"14;
%"Q_CAPP"
"1","(-1625,2775)","0","pure_quanta","I153";
;
LOCATION"PC391"
$SEC"1"
CDS_SEC"1"
PACK_TYPE"SMLF"
VOLTAGE"4V"
VALUE"220UF"
TOLERANCE"20%"
MATERIAL"SPCAP"
PART_NUMBER"CH122KM8801"
CDS_LIB"pure_quanta";
"A"
$PN"1"14;
"B"
$PN"2"15;
%"Q_CAP"
"1","(-6150,5350)","0","pure_quanta","I154";
;
LOCATION"PC375_1"
$SEC"1"
CDS_SEC"1"
MATERIAL"X7R"
TOLERANCE"10%"
VALUE"0.1UF"
PART_NUMBER"CH4104K1B00"
VOLTAGE"25V"
PACK_TYPE"0402"
CDS_LIB"pure_quanta";
"B"
$PN"2"57;
"A"
$PN"1"44;
%"Q_CAP"
"1","(-6125,2725)","0","pure_quanta","I155";
;
LOCATION"PC376_2"
$SEC"1"
CDS_SEC"1"
MATERIAL"X7R"
TOLERANCE"10%"
VALUE"0.1UF"
PART_NUMBER"CH4104K1B00"
VOLTAGE"25V"
PACK_TYPE"0402"
CDS_LIB"pure_quanta";
"B"
$PN"2"53;
"A"
$PN"1"36;
%"Q_CAP"
"1","(-8700,4900)","0","pure_quanta","I156";
;
LOCATION"PC369"
$SEC"1"
CDS_SEC"1"
MATERIAL"X6S"
TOLERANCE"10%"
VALUE"2.2UF"
PART_NUMBER"CH5222KEB01"
VOLTAGE"10V"
PACK_TYPE"C0402"
CDS_LIB"pure_quanta";
"B"
$PN"2"3;
"A"
$PN"1"20;
%"UNIVERSAL_GND"
"1","(-8700,4700)","0","pure_quanta_power","I157";
;
CDS_LIB"pure_quanta_power"
HDL_POWER"GND";
"A"3;
%"UNIVERSAL_GND"
"1","(-8350,5200)","0","pure_quanta_power","I158";
;
CDS_LIB"pure_quanta_power"
HDL_POWER"GND";
"A"4;
%"Q_RES"
"2","(-8700,5450)","0","pure_quanta","I159";
;
LOCATION"PR256"
$SEC"1"
CDS_SEC"1"
PART_NUMBER"CS-2202FB00"
WATTAGE"1/16W"
MATERIAL"CHIP"
TOLERANCE"1%"
VALUE"2.2"
PACK_TYPE"0402LF"
CDS_LIB"pure_quanta";
"A"
$PN"1"26;
"B"
$PN"2"20;
%"Q_CAP"
"1","(-8350,5475)","0","pure_quanta","I160";
;
LOCATION"PC371_C1P1_1"
$SEC"1"
CDS_SEC"1"
MATERIAL"X6S"
TOLERANCE"10%"
VALUE"2.2UF"
PART_NUMBER"CH5222KEB01"
VOLTAGE"10V"
PACK_TYPE"C0402"
CDS_LIB"pure_quanta";
"B"
$PN"2"4;
"A"
$PN"1"26;
%"VCC_CORE"
"1","(-8500,6050)","0","pure_quanta_power","I161";
;
HDL_POWER"PVDDCR_CPU1_P1_PVCC"
CDS_LIB"pure_quanta_power";
"A"26;
%"Q_CAP"
"1","(-8600,2250)","0","pure_quanta","I162";
;
LOCATION"PC370"
$SEC"1"
CDS_SEC"1"
MATERIAL"X6S"
TOLERANCE"10%"
VALUE"2.2UF"
PART_NUMBER"CH5222KEB01"
VOLTAGE"10V"
PACK_TYPE"C0402"
CDS_LIB"pure_quanta";
"B"
$PN"2"5;
"A"
$PN"1"29;
%"UNIVERSAL_GND"
"1","(-8600,2050)","0","pure_quanta_power","I163";
;
CDS_LIB"pure_quanta_power"
HDL_POWER"GND";
"A"5;
%"UNIVERSAL_GND"
"1","(-8250,2550)","0","pure_quanta_power","I164";
;
CDS_LIB"pure_quanta_power"
HDL_POWER"GND";
"A"6;
%"Q_RES"
"2","(-8600,2800)","0","pure_quanta","I165";
;
LOCATION"PR257"
$SEC"1"
CDS_SEC"1"
WATTAGE"1/16W"
MATERIAL"CHIP"
TOLERANCE"1%"
VALUE"2.2"
PART_NUMBER"CS-2202FB00"
PACK_TYPE"0402LF"
CDS_LIB"pure_quanta";
"A"
$PN"1"60;
"B"
$PN"2"29;
%"Q_CAP"
"1","(-8250,2825)","0","pure_quanta","I166";
;
LOCATION"PC372_C1P1_2"
$SEC"1"
CDS_SEC"1"
MATERIAL"X6S"
TOLERANCE"10%"
VALUE"2.2UF"
PART_NUMBER"CH5222KEB01"
VOLTAGE"10V"
PACK_TYPE"C0402"
CDS_LIB"pure_quanta";
"B"
$PN"2"6;
"A"
$PN"1"60;
%"UNIVERSAL_GND"
"1","(-9350,3875)","0","pure_quanta_power","I168";
;
CDS_LIB"pure_quanta_power"
HDL_POWER"GND";
"A"7;
%"UNIVERSAL_GND"
"1","(-9375,1250)","0","pure_quanta_power","I169";
;
CDS_LIB"pure_quanta_power"
HDL_POWER"GND";
"A"8;
%"Q_CAPP"
"1","(-2925,2775)","0","pure_quanta","I170";
;
LOCATION"PC106"
$SEC"1"
CDS_SEC"1"
VOLTAGE"4V"
TOLERANCE"20%"
PACK_TYPE"SMLF"
MATERIAL"SPCAP"
PART_NUMBER"CH122KM8801"
VALUE"220UF"
CDS_LIB"pure_quanta";
"A"
$PN"1"14;
"B"
$PN"2"15;
%"UNIVERSAL_GND"
"1","(-5450,3500)","0","pure_quanta_power","I172";
;
CDS_LIB"pure_quanta_power"
HDL_POWER"GND";
"A"9;
%"Q_RES"
"2","(-5450,3725)","0","pure_quanta","I173";
;
LOCATION"PR512"
$SEC"1"
CDS_SEC"1"
WATTAGE"1/8W"
PART_NUMBER"CS-1504FB00"
MATERIAL"EMPTY"
TOLERANCE"1%"
VALUE"1.5"
PACK_TYPE"0402LF"
CDS_LIB"pure_quanta";
"A"
$PN"1"42;
"B"
$PN"2"9;
%"Q_CAP"
"1","(-5450,4250)","0","pure_quanta","I174";
;
LOCATION"PC201"
$SEC"1"
CDS_SEC"1"
MATERIAL"EMPTY"
TOLERANCE"10%"
VALUE"560PF"
PART_NUMBER"CH1566K1B09"
VOLTAGE"50V"
PACK_TYPE"C0402"
CDS_LIB"pure_quanta";
"B"
$PN"2"42;
"A"
$PN"1"56;
%"UNIVERSAL_GND"
"1","(-5500,875)","0","pure_quanta_power","I175";
;
CDS_LIB"pure_quanta_power"
HDL_POWER"GND";
"A"10;
%"Q_RES"
"2","(-5500,1100)","0","pure_quanta","I176";
;
LOCATION"PR513"
$SEC"1"
CDS_SEC"1"
WATTAGE"1/8W"
MATERIAL"EMPTY"
TOLERANCE"1%"
VALUE"1.5"
PART_NUMBER"CS-1504FB00"
PACK_TYPE"0402LF"
CDS_LIB"pure_quanta";
"A"
$PN"1"41;
"B"
$PN"2"10;
%"Q_CAP"
"1","(-5500,1650)","0","pure_quanta","I177";
;
LOCATION"PC202"
$SEC"1"
CDS_SEC"1"
TOLERANCE"10%"
MATERIAL"EMPTY"
PART_NUMBER"CH1566K1B09"
VALUE"560PF"
VOLTAGE"50V"
PACK_TYPE"C0402"
CDS_LIB"pure_quanta";
"B"
$PN"2"41;
"A"
$PN"1"22;
%"Q_RES"
"1","(-9350,5850)","1","pure_quanta","I179";
;
LOCATION"PR340"
$SEC"1"
CDS_SEC"1"
WATTAGE"1/16W"
MATERIAL"CHIP"
TOLERANCE"5%"
VALUE"0"
PART_NUMBER"CS00002JB38"
PACK_TYPE"0402LF"
CDS_LIB"pure_quanta";
"B"
$PN"2"11;
"A"
$PN"1"26;
%"VCC_CORE"
"1","(-9350,6050)","0","pure_quanta_power","I180";
;
HDL_POWER"P5V_STBY"
CDS_LIB"pure_quanta_power";
"A"11;
%"Q_RES"
"1","(-9000,5850)","1","pure_quanta","I181";
;
LOCATION"PR341"
$SEC"1"
CDS_SEC"1"
WATTAGE"1/16W"
MATERIAL"EMPTY"
TOLERANCE"5%"
VALUE"0"
PART_NUMBER"CS00002JB38"
PACK_TYPE"0402LF"
CDS_LIB"pure_quanta";
"B"
$PN"2"12;
"A"
$PN"1"26;
%"VCC_CORE"
"1","(-9000,6050)","0","pure_quanta_power","I182";
;
HDL_POWER"P3V3_STBY"
CDS_LIB"pure_quanta_power";
"A"12;
%"VCC_CORE"
"1","(-8600,3200)","0","pure_quanta_power","I183";
;
HDL_POWER"PVDDCR_CPU1_P1_PVCC"
CDS_LIB"pure_quanta_power";
"A"60;
%"Q_RES"
"2","(-1025,4250)","0","pure_quanta","I184";
;
LOCATION"PR342"
$SEC"1"
CDS_SEC"1"
WATTAGE"1/16W"
MATERIAL"CHIP"
TOLERANCE"1%"
VALUE"1K"
PART_NUMBER"TMP_QCS21002FB24"
PACK_TYPE"0402LF"
CDS_LIB"pure_quanta";
"A"
$PN"1"17;
"B"
$PN"2"51;
%"VCC_CORE"
"1","(-4750,5750)","0","pure_quanta_power","I185";
;
HDL_POWER"SW_P12V_STBY_PVDDCR_CPU1_P1_FLT"
CDS_LIB"pure_quanta_power";
"A"44;
%"UNIVERSAL_GND"
"1","(-6300,1100)","0","pure_quanta_power","I19";
;
CDS_LIB"pure_quanta_power"
HDL_POWER"GND";
"A"35;
%"Q_RES"
"2","(-8875,1325)","2","pure_quanta","I2";
;
LOCATION"PR254"
$SEC"1"
CDS_SEC"1"
WATTAGE"1/16W"
MATERIAL"EMPTY"
TOLERANCE"1%"
VALUE"8.87K"
PART_NUMBER"CS28872FB01"
PACK_TYPE"0402LF"
CDS_LIB"pure_quanta";
"A"
$PN"1"28;
"B"
$PN"2"1;
%"ISL99390FRZTR5935"
"1","(-6925,4450)","0","pure_quanta","I21";
;
LOCATION"PU35"
$SEC"1"
CDS_SEC"1"
PART_TYPE"SMLF"
MATERIAL"IC"
VALUE"ISL99390FRZ-TR5935"
PART_NUMBER"AL099390004"
NEEDS_NO_SIZE"TRUE"
CDS_LMAN_SYM_OUTLINE"-300,700,250,-650"
CDS_LIB"pure_quanta";
"PGND2"
$PN"7_9-20_24"19;
"GL2"
$PN"41"25;
"GL1"
$PN"6"45;
"DNC"
$PN"31"43;
"EN"
$PN"35"20;
"PGND3"
$PN"40"19;
"VOS"
$PN"1"18;
"VIN2"
$PN"30"44;
"PGND1"
$PN"5"19;
"SW"
$PN"10_19"56;
"LSET"
$PN"37"27;
"IOUT"
$PN"38"59;
"TOUT_FLT"
$PN"36"16;
"PVCC"
$PN"4"26;
"PHASE"
$PN"32"55;
"VIN1"
$PN"25_29"44;
"BOOT"
$PN"33"46;
"AGND"
$PN"2"19;
"VCC"
$PN"3"20;
"REFIN"
$PN"39"58;
"PWM"
$PN"34"31;
%"Q_CAP"
"1","(-5725,2725)","0","pure_quanta","I23";
;
LOCATION"PC378_2"
$SEC"1"
CDS_SEC"1"
MATERIAL"X6S"
TOLERANCE"10%"
VALUE"1UF"
PART_NUMBER"CH5104KEB02"
VOLTAGE"25V"
PACK_TYPE"C0402"
CDS_LIB"pure_quanta";
"B"
$PN"2"53;
"A"
$PN"1"36;
%"Q_CAP"
"1","(-5325,2725)","0","pure_quanta","I24";
;
LOCATION"PC380_2"
$SEC"1"
CDS_SEC"1"
MATERIAL"X6S"
TOLERANCE"10%"
VALUE"10UF"
PART_NUMBER"CH6104KEA00"
VOLTAGE"25V"
PACK_TYPE"C0805"
CDS_LIB"pure_quanta";
"B"
$PN"2"53;
"A"
$PN"1"36;
%"UNIVERSAL_GND"
"1","(-6275,3725)","0","pure_quanta_power","I25";
;
CDS_LIB"pure_quanta_power"
HDL_POWER"GND";
"A"19;
%"Q_CAP"
"1","(-5750,5350)","0","pure_quanta","I41";
;
LOCATION"PC377_1"
$SEC"1"
CDS_SEC"1"
MATERIAL"X6S"
TOLERANCE"10%"
VALUE"1UF"
PART_NUMBER"CH5104KEB02"
VOLTAGE"25V"
PACK_TYPE"C0402"
CDS_LIB"pure_quanta";
"B"
$PN"2"57;
"A"
$PN"1"44;
%"Q_CAP"
"1","(-4925,2725)","0","pure_quanta","I46";
;
LOCATION"PC382_2"
$SEC"1"
CDS_SEC"1"
TOLERANCE"10%"
VALUE"10UF"
VOLTAGE"25V"
MATERIAL"X6S"
PACK_TYPE"C0805"
PART_NUMBER"CH6104KEA00"
CDS_LIB"pure_quanta";
"B"
$PN"2"53;
"A"
$PN"1"36;
%"Q_CAP"
"1","(-4550,2725)","0","pure_quanta","I47";
;
LOCATION"PC385_2"
$SEC"1"
CDS_SEC"1"
MATERIAL"X6S"
TOLERANCE"10%"
VALUE"10UF"
PART_NUMBER"CH6104KEA00"
VOLTAGE"25V"
PACK_TYPE"C0805"
CDS_LIB"pure_quanta";
"B"
$PN"2"53;
"A"
$PN"1"36;
%"UNIVERSAL_GND"
"1","(-4550,2350)","0","pure_quanta_power","I48";
;
CDS_LIB"pure_quanta_power"
HDL_POWER"GND";
"A"53;
%"VCC_CORE"
"1","(-4550,3075)","0","pure_quanta_power","I49";
;
HDL_POWER"SW_P12V_STBY_PVDDCR_CPU1_P1_FLT"
CDS_LIB"pure_quanta_power";
"A"36;
%"UNIVERSAL_GND"
"1","(-4700,4950)","0","pure_quanta_power","I64";
;
CDS_LIB"pure_quanta_power"
HDL_POWER"GND";
"A"57;
%"Q_CAP"
"1","(-5350,5350)","0","pure_quanta","I65";
;
LOCATION"PC379_1"
$SEC"1"
CDS_SEC"1"
TOLERANCE"10%"
VOLTAGE"25V"
MATERIAL"X6S"
PACK_TYPE"C0805"
PART_NUMBER"CH6104KEA00"
VALUE"10UF"
CDS_LIB"pure_quanta";
"B"
$PN"2"57;
"A"
$PN"1"44;
%"Q_CAP"
"1","(-4950,5350)","0","pure_quanta","I66";
;
LOCATION"PC381_1"
$SEC"1"
CDS_SEC"1"
VALUE"10UF"
MATERIAL"X6S"
TOLERANCE"10%"
VOLTAGE"25V"
PACK_TYPE"C0805"
PART_NUMBER"CH6104KEA00"
CDS_LIB"pure_quanta";
"B"
$PN"2"57;
"A"
$PN"1"44;
%"Q_CAP"
"1","(-4575,5350)","0","pure_quanta","I67";
;
LOCATION"PC384_1"
$SEC"1"
CDS_SEC"1"
PART_NUMBER"CH6104KEA00"
PACK_TYPE"C0805"
VOLTAGE"25V"
MATERIAL"X6S"
TOLERANCE"10%"
VALUE"10UF"
CDS_LIB"pure_quanta";
"B"
$PN"2"57;
"A"
$PN"1"44;
%"VCC_CORE"
"1","(-3200,5725)","0","pure_quanta_power","I73";
;
HDL_POWER"P12V_STBY"
CDS_LIB"pure_quanta_power";
"A"13;
%"Q_CAPP"
"1","(-4250,5350)","0","pure_quanta","I74";
;
LOCATION"PC390"
$SEC"1"
CDS_SEC"1"
PART_NUMBER"CC72204MD02"
MATERIAL"OSCON"
VOLTAGE"25V"
TOLERANCE"20%"
VALUE"220UF"
PACK_TYPE"THLF"
CDS_LIB"pure_quanta";
"A"
$PN"1"44;
"B"
$PN"2"57;
%"Q_INDUCTOR"
"1","(-3475,5625)","0","pure_quanta","I75";
;
LOCATION"PL42"
$SEC"1"
CDS_SEC"1"
MATERIAL"IND"
VALUE"50NH/86A"
PART_NUMBER"CVA50^0MZ09"
PACK_TYPE"SMLF"
NEEDS_NO_SIZE"TRUE"
CDS_LIB"pure_quanta";
"1"
$PN"1"44;
"2"
$PN"2"13;
%"Q_CAPP"
"1","(-3850,5350)","0","pure_quanta","I76";
;
LOCATION"PC393"
$SEC"1"
CDS_SEC"1"
PART_NUMBER"CC72204MD02"
MATERIAL"OSCON"
TOLERANCE"20%"
VALUE"220UF"
VOLTAGE"25V"
PACK_TYPE"THLF"
CDS_LIB"pure_quanta";
"A"
$PN"1"44;
"B"
$PN"2"57;
%"ISL99390FRZTR5935"
"1","(-6950,1825)","0","pure_quanta","I87";
;
LOCATION"PU5"
SEC"1"
PART_TYPE"SMLF"
VALUE"ISL99390FRZ-TR5935"
PART_NUMBER"AL099390004"
MATERIAL"IC"
SEC_TYPE""
CDS_LIB"pure_quanta"
CDS_LMAN_SYM_OUTLINE"-300,700,250,-650"
NEEDS_NO_SIZE"TRUE";
"PGND2"
$PN"7_9-20_24"35;
"GL2"
$PN"41"39;
"GL1"
$PN"6"38;
"DNC"
$PN"31"34;
"EN"
$PN"35"29;
"PGND3"
$PN"40"35;
"VOS"
$PN"1"40;
"VIN2"
$PN"30"36;
"PGND1"
$PN"5"35;
"SW"
$PN"10_19"22;
"LSET"
$PN"37"28;
"IOUT"
$PN"38"30;
"TOUT_FLT"
$PN"36"33;
"PVCC"
$PN"4"60;
"PHASE"
$PN"32"21;
"VIN1"
$PN"25_29"36;
"BOOT"
$PN"33"37;
"AGND"
$PN"2"35;
"VCC"
$PN"3"29;
"REFIN"
$PN"39"61;
"PWM"
$PN"34"32;
END.
